# BASEBOARD_FAB2 (Tioga Pass) — schematic netlist excerpt (pin names and nets, part order shuffled) for the footprints in the layout excerpt that follows; sources: Cadence DE-HDL packaged netlist, KiCad conversion of Wiwynn_Tioga_Pass_MB.brd

R3N11  RES  4.75K 1% CHIP  pkg 0402  page 157 : A = P3V3_STBY ; B = FM_MP_PS_REDUNDANT_LOST_N
R3P63  RES  0.0 5% EMPTY  pkg 0402  page 152 : A = H_CPU1_MEMGHJ_MEMHOT_LVT3_N ; B = H_CPU1_MEMGHJ_MEMHOT_PCH_N

(kicad_pcb
	(version 20260206)
	(generator "pcbnew")
	(generator_version "10.0")
	(general
		(thickness 1.6)
		(legacy_teardrops no)
	)
	(paper "A4")
	(title_block
		(title "Wiwynn_Tioga_Pass_MB.brd")
		(comment 1 "Tioga Pass / footprints 4715-4717 of 4770")
	)
	(layers
		(0 "F.Cu" signal "TOP")
		(4 "In1.Cu" signal "L2GND")
		(6 "In2.Cu" signal "L3")
		(8 "In3.Cu" signal "L4GND")
		(10 "In4.Cu" signal "L5")
		(12 "In5.Cu" signal "L6GND")
		(14 "In6.Cu" signal "L7VCC")
		(16 "In7.Cu" signal "L8VCC")
		(18 "In8.Cu" signal "L9GND")
		(20 "In9.Cu" signal "L10")
		(22 "In10.Cu" signal "L11GND")
		(24 "In11.Cu" signal "L12")
		(26 "In12.Cu" signal "L13GND")
		(2 "B.Cu" signal "BOTTOM")
		(9 "F.Adhes" user "F.Adhesive")
		(11 "B.Adhes" user "B.Adhesive")
		(13 "F.Paste" user "Package Geometry/Pastemask Top")
		(15 "B.Paste" user "Package Geometry/Pastemask Bottom")
		(5 "F.SilkS" user "Ref Des/Silkscreen Top")
		(7 "B.SilkS" user "Ref Des/Silkscreen Bottom")
		(1 "F.Mask" user "Board Geometry/Soldermask Top")
		(3 "B.Mask" user "Board Geometry/Soldermask Bottom")
		(17 "Dwgs.User" user "User.Drawings")
		(19 "Cmts.User" user "User.Comments")
		(21 "Eco1.User" user "User.Eco1")
		(23 "Eco2.User" user "User.Eco2")
		(25 "Edge.Cuts" user "Board Geometry/Outline")
		(27 "Margin" user)
		(31 "F.CrtYd" user "Package Geometry/Place Bound Top")
		(29 "B.CrtYd" user "Package Geometry/Place Bound Bottom")
		(35 "F.Fab" user "Ref Des/Assembly Top")
		(33 "B.Fab" user "Ref Des/Assembly Bottom")
	)
	(footprint ""
		(layer "B.Cu")
		(at 387.604 -87.3125 180)
		(property "Reference" "R3N11"
			(at 0 0 0)
			(layer "B.SilkS")
			(hide yes)
			(effects
				(font
					(size 1.27 1.27)
				)
				(justify mirror)
			)
		)
		(property "Value" ""
			(at 0 0 0)
			(layer "B.Fab")
			(effects
				(font
					(size 1.27 1.27)
				)
				(justify mirror)
			)
		)
		(duplicate_pad_numbers_are_jumpers no)
		(fp_poly
			(pts
				(xy 0.2794 -0.1016) (xy -0.2794 -0.1016) (xy -0.2794 0.9906) (xy 0.2794 0.9906)
			)
			(stroke
				(width 0)
				(type default)
			)
			(fill no)
			(layer "B.CrtYd")
		)
		(fp_line
			(start 0.2794 0.9906)
			(end -0.2794 0.9906)
			(stroke
				(width 0.1)
				(type default)
			)
			(layer "B.Fab")
		)
		(fp_line
			(start 0.2794 -0.1016)
			(end 0.2794 0.9906)
			(stroke
				(width 0.1)
				(type default)
			)
			(layer "B.Fab")
		)
		(fp_line
			(start -0.2794 0.9906)
			(end -0.2794 -0.1016)
			(stroke
				(width 0.1)
				(type default)
			)
			(layer "B.Fab")
		)
		(fp_line
			(start -0.2794 -0.1016)
			(end 0.2794 -0.1016)
			(stroke
				(width 0.1)
				(type default)
			)
			(layer "B.Fab")
		)
		(pad "1" smd rect
			(at 0 0)
			(size 0.508 0.508)
			(layers "B.Cu" "B.Mask" "B.Paste")
			(net "P3V3_STBY")
		)
		(pad "2" smd rect
			(at 0 0.889)
			(size 0.508 0.508)
			(layers "B.Cu" "B.Mask" "B.Paste")
			(net "FM_MP_PS_REDUNDANT_LOST_N")
		)
		(zone
			(layer "B.Cu")
			(hatch none 0.5)
			(connect_pads
				(clearance 0)
			)
			(min_thickness 0.25)
			(keepout
				(tracks not_allowed)
				(vias allowed)
				(pads allowed)
				(copperpour not_allowed)
				(footprints allowed)
			)
			(placement
				(enabled no)
				(sheetname "")
			)
			(fill
				(thermal_gap 0.5)
				(thermal_bridge_width 0.5)
				(island_removal_mode 0)
			)
			(polygon
				(pts
					(xy 387.35 -87.9475) (xy 387.858 -87.9475) (xy 387.858 -87.5665) (xy 387.35 -87.5665)
				)
			)
		)
		(zone
			(layer "B.Cu")
			(hatch none 0.5)
			(connect_pads
				(clearance 0)
			)
			(min_thickness 0.25)
			(keepout
				(tracks allowed)
				(vias not_allowed)
				(pads allowed)
				(copperpour not_allowed)
				(footprints allowed)
			)
			(placement
				(enabled no)
				(sheetname "")
			)
			(fill
				(thermal_gap 0.5)
				(thermal_bridge_width 0.5)
				(island_removal_mode 0)
			)
			(polygon
				(pts
					(xy 387.35 -87.5665) (xy 387.858 -87.5665) (xy 387.858 -87.9475) (xy 387.35 -87.9475)
				)
			)
		)
	)
	(footprint ""
		(layer "B.Cu")
		(at 388.66064 -80.2386 -90)
		(property "Reference" "R3P63"
			(at 0.8382 -0.67818 270)
			(unlocked yes)
			(layer "B.SilkS")
			(effects
				(font
					(size 0.4064 0.254)
					(thickness 0.1524)
				)
				(justify left mirror)
			)
		)
		(property "Value" ""
			(at 0 0 90)
			(layer "B.Fab")
			(effects
				(font
					(size 1.27 1.27)
				)
				(justify mirror)
			)
		)
		(duplicate_pad_numbers_are_jumpers no)
		(fp_poly
			(pts
				(xy 0.2794 -0.1016) (xy -0.2794 -0.1016) (xy -0.2794 0.9906) (xy 0.2794 0.9906)
			)
			(stroke
				(width 0)
				(type default)
			)
			(fill no)
			(layer "B.CrtYd")
		)
		(fp_line
			(start -0.2794 0.9906)
			(end -0.2794 -0.1016)
			(stroke
				(width 0.1)
				(type default)
			)
			(layer "B.Fab")
		)
		(fp_line
			(start 0.2794 0.9906)
			(end -0.2794 0.9906)
			(stroke
				(width 0.1)
				(type default)
			)
			(layer "B.Fab")
		)
		(fp_line
			(start -0.2794 -0.1016)
			(end 0.2794 -0.1016)
			(stroke
				(width 0.1)
				(type default)
			)
			(layer "B.Fab")
		)
		(fp_line
			(start 0.2794 -0.1016)
			(end 0.2794 0.9906)
			(stroke
				(width 0.1)
				(type default)
			)
			(layer "B.Fab")
		)
		(pad "1" smd rect
			(at 0 0 90)
			(size 0.508 0.508)
			(layers "B.Cu" "B.Mask" "B.Paste")
			(net "H_CPU1_MEMGHJ_MEMHOT_LVT3_N")
		)
		(pad "2" smd rect
			(at 0 0.889 90)
			(size 0.508 0.508)
			(layers "B.Cu" "B.Mask" "B.Paste")
			(net "H_CPU1_MEMGHJ_MEMHOT_PCH_N")
		)
		(zone
			(layer "B.Cu")
			(hatch none 0.5)
			(connect_pads
				(clearance 0)
			)
			(min_thickness 0.25)
			(keepout
				(tracks not_allowed)
				(vias allowed)
				(pads allowed)
				(copperpour not_allowed)
				(footprints allowed)
			)
			(placement
				(enabled no)
				(sheetname "")
			)
			(fill
				(thermal_gap 0.5)
				(thermal_bridge_width 0.5)
				(island_removal_mode 0)
			)
			(polygon
				(pts
					(xy 388.02564 -79.9846) (xy 388.02564 -80.4926) (xy 388.40664 -80.4926) (xy 388.40664 -79.9846)
				)
			)
		)
		(zone
			(layer "B.Cu")
			(hatch none 0.5)
			(connect_pads
				(clearance 0)
			)
			(min_thickness 0.25)
			(keepout
				(tracks allowed)
				(vias not_allowed)
				(pads allowed)
				(copperpour not_allowed)
				(footprints allowed)
			)
			(placement
				(enabled no)
				(sheetname "")
			)
			(fill
				(thermal_gap 0.5)
				(thermal_bridge_width 0.5)
				(island_removal_mode 0)
			)
			(polygon
				(pts
					(xy 388.40664 -79.9846) (xy 388.40664 -80.4926) (xy 388.02564 -80.4926) (xy 388.02564 -79.9846)
				)
			)
		)
	)
	(footprint ""
		(layer "B.Cu")
		(at 488.95 -15.748)
		(property "Reference" ""
			(at 0 0 0)
			(layer "B.SilkS")
			(hide yes)
			(effects
				(font
					(size 1.27 1.27)
				)
				(justify mirror)
			)
		)
		(property "Value" ""
			(at 0 0 0)
			(layer "B.Fab")
			(effects
				(font
					(size 1.27 1.27)
				)
				(justify mirror)
			)
		)
		(duplicate_pad_numbers_are_jumpers no)
		(fp_poly
			(pts
				(arc
					(start 2.032 0)
					(mid -2.032 0)
					(end 2.032 0)
				)
			)
			(stroke
				(width 0)
				(type default)
			)
			(fill no)
			(layer "B.CrtYd")
		)
		(pad "1" smd circle
			(at 0 0 180)
			(size 1.016 1.016)
			(layers "B.Cu" "B.Mask" "B.Paste")
			(net "Net_128")
		)
		(zone
			(layers "F.Cu" "B.Cu" "In1.Cu" "In2.Cu" "In3.Cu" "In4.Cu" "In5.Cu" "In6.Cu"
				"In7.Cu" "In8.Cu" "In9.Cu" "In10.Cu" "In11.Cu" "In12.Cu"
			)
			(hatch none 0.5)
			(connect_pads
				(clearance 0)
			)
			(min_thickness 0.25)
			(keepout
				(tracks allowed)
				(vias not_allowed)
				(pads allowed)
				(copperpour not_allowed)
				(footprints allowed)
			)
			(placement
				(enabled no)
				(sheetname "")
			)
			(fill
				(thermal_gap 0.5)
				(thermal_bridge_width 0.5)
				(island_removal_mode 0)
			)
			(polygon
				(pts
					(arc
						(start 490.474 -15.748)
						(mid 487.426 -15.748)
						(end 490.474 -15.748)
					)
				)
			)
		)
		(zone
			(layer "B.Cu")
			(hatch none 0.5)
			(connect_pads
				(clearance 0)
			)
			(min_thickness 0.25)
			(keepout
				(tracks not_allowed)
				(vias allowed)
				(pads allowed)
				(copperpour not_allowed)
				(footprints allowed)
			)
			(placement
				(enabled no)
				(sheetname "")
			)
			(fill
				(thermal_gap 0.5)
				(thermal_bridge_width 0.5)
				(island_removal_mode 0)
			)
			(polygon
				(pts
					(arc
						(start 490.474 -15.748)
						(mid 487.426 -15.748)
						(end 490.474 -15.748)
					)
				)
			)
		)
	)
)
